# T6G (Grand Teton) — schematic netlist excerpt (pin names and nets, part order shuffled) for the footprints in the layout excerpt that follows; sources: Cadence DE-HDL packaged netlist, KiCad conversion of 04192023_DAF0TMB3IC0_F0TG_MB_C_brd_V02_OCP.brd

C913  Q_CAP_DIFFBUS  DIFF BUS_0.22UF 6.3V 20% X6S  pkg C0201  page 63 : \1\ = P5E_CPU0_P0_TX_C_DP<10> ; \2\ = P5E_CPU0_P0_TX_DP<10>
C809  Q_CAP_DIFFBUS  DIFF BUS_0.22UF 6.3V 20% X6S  pkg C0201  page 65 : \1\ = P5E_CPU1_P0_TX_C_DP<14> ; \2\ = P5E_CPU1_P0_TX_DP<14>
C1  Q_CAP  0.1UF 25V 10% X7R  pkg 0402  page 238 : A = P3V3_AUX ; B = GND

(kicad_pcb
	(version 20260206)
	(generator "pcbnew")
	(generator_version "10.0")
	(general
		(thickness 1.6)
		(legacy_teardrops no)
	)
	(paper "A4")
	(title_block
		(title "04192023_DAF0TMB3IC0_F0TG_MB_C_brd_V02_OCP.brd")
		(comment 1 "Grand Teton / footprints 2741-2743 of 8354")
	)
	(layers
		(0 "F.Cu" signal "TOP")
		(4 "In1.Cu" signal "GND")
		(6 "In2.Cu" signal "IN1")
		(8 "In3.Cu" signal "GND1")
		(10 "In4.Cu" signal "IN2")
		(12 "In5.Cu" signal "GND2")
		(14 "In6.Cu" signal "IN3")
		(16 "In7.Cu" signal "GND3")
		(18 "In8.Cu" signal "VCC")
		(20 "In9.Cu" signal "VCC1")
		(22 "In10.Cu" signal "GND4")
		(24 "In11.Cu" signal "IN4")
		(26 "In12.Cu" signal "GND5")
		(28 "In13.Cu" signal "IN5")
		(30 "In14.Cu" signal "GND6")
		(32 "In15.Cu" signal "IN6")
		(34 "In16.Cu" signal "GND7")
		(2 "B.Cu" signal "BOTTOM")
		(9 "F.Adhes" user "F.Adhesive")
		(11 "B.Adhes" user "B.Adhesive")
		(13 "F.Paste" user "Package Geometry/Pastemask Top")
		(15 "B.Paste" user "Package Geometry/Pastemask Bottom")
		(5 "F.SilkS" user "Ref Des/Silkscreen Top")
		(7 "B.SilkS" user "Ref Des/Silkscreen Bottom")
		(1 "F.Mask" user "Board Geometry/Soldermask Top")
		(3 "B.Mask" user "Board Geometry/Soldermask Bottom")
		(17 "Dwgs.User" user "User.Drawings")
		(19 "Cmts.User" user "User.Comments")
		(21 "Eco1.User" user "User.Eco1")
		(23 "Eco2.User" user "User.Eco2")
		(25 "Edge.Cuts" user "Board Geometry/Outline")
		(27 "Margin" user)
		(31 "F.CrtYd" user "Package Geometry/Place Bound Top")
		(29 "B.CrtYd" user "Package Geometry/Place Bound Bottom")
		(35 "F.Fab" user "Ref Des/Assembly Top")
		(33 "B.Fab" user "Ref Des/Assembly Bottom")
	)
	(footprint ""
		(layer "F.Cu")
		(at 314.567316 -113.60277)
		(property "Reference" "C1"
			(at 0 0 0)
			(layer "F.SilkS")
			(hide yes)
			(effects
				(font
					(size 1.27 1.27)
				)
			)
		)
		(property "Value" ""
			(at 0 0 0)
			(layer "F.Fab")
			(effects
				(font
					(size 1.27 1.27)
				)
			)
		)
		(duplicate_pad_numbers_are_jumpers no)
		(fp_line
			(start -0.7874 -0.4064)
			(end 0.7874 -0.4064)
			(stroke
				(width 0.1524)
				(type default)
			)
			(layer "F.SilkS")
		)
		(fp_line
			(start -0.7874 0.4064)
			(end -0.7874 -0.4064)
			(stroke
				(width 0.1524)
				(type default)
			)
			(layer "F.SilkS")
		)
		(fp_line
			(start 0.7874 -0.4064)
			(end 0.7874 0.4064)
			(stroke
				(width 0.1524)
				(type default)
			)
			(layer "F.SilkS")
		)
		(fp_line
			(start 0.7874 0.4064)
			(end -0.7874 0.4064)
			(stroke
				(width 0.1524)
				(type default)
			)
			(layer "F.SilkS")
		)
		(fp_line
			(start -0.67945 -0.305054)
			(end -0.12065 -0.305054)
			(stroke
				(width 0.1)
				(type default)
			)
			(layer "F.Fab")
		)
		(fp_line
			(start -0.67945 0.3048)
			(end -0.67945 -0.305054)
			(stroke
				(width 0.1)
				(type default)
			)
			(layer "F.Fab")
		)
		(fp_line
			(start -0.12065 -0.305054)
			(end -0.12065 -0.2794)
			(stroke
				(width 0.1)
				(type default)
			)
			(layer "F.Fab")
		)
		(fp_line
			(start -0.12065 -0.2794)
			(end 0.12065 -0.2794)
			(stroke
				(width 0.1)
				(type default)
			)
			(layer "F.Fab")
		)
		(fp_line
			(start -0.12065 0.2794)
			(end -0.12065 0.3048)
			(stroke
				(width 0.1)
				(type default)
			)
			(layer "F.Fab")
		)
		(fp_line
			(start -0.12065 0.3048)
			(end -0.67945 0.3048)
			(stroke
				(width 0.1)
				(type default)
			)
			(layer "F.Fab")
		)
		(fp_line
			(start 0.120396 0.2794)
			(end -0.12065 0.2794)
			(stroke
				(width 0.1)
				(type default)
			)
			(layer "F.Fab")
		)
		(fp_line
			(start 0.120396 0.3048)
			(end 0.120396 0.2794)
			(stroke
				(width 0.1)
				(type default)
			)
			(layer "F.Fab")
		)
		(fp_line
			(start 0.12065 -0.3048)
			(end 0.67945 -0.3048)
			(stroke
				(width 0.1)
				(type default)
			)
			(layer "F.Fab")
		)
		(fp_line
			(start 0.12065 -0.2794)
			(end 0.12065 -0.3048)
			(stroke
				(width 0.1)
				(type default)
			)
			(layer "F.Fab")
		)
		(fp_line
			(start 0.67945 -0.3048)
			(end 0.67945 0.3048)
			(stroke
				(width 0.1)
				(type default)
			)
			(layer "F.Fab")
		)
		(fp_line
			(start 0.67945 0.3048)
			(end 0.120396 0.3048)
			(stroke
				(width 0.1)
				(type default)
			)
			(layer "F.Fab")
		)
		(pad "1" smd circle
			(at -0.40005 0)
			(size 0 0)
			(layers "F.Cu" "F.Mask" "F.Paste")
			(net "P3V3_AUX")
		)
		(pad "2" smd circle
			(at 0.40005 0)
			(size 0 0)
			(layers "F.Cu" "F.Mask" "F.Paste")
			(net "GND")
		)
	)
	(footprint ""
		(layer "F.Cu")
		(at 69.741034 -376.067828)
		(property "Reference" "C809"
			(at 0 0 0)
			(layer "F.SilkS")
			(hide yes)
			(effects
				(font
					(size 1.27 1.27)
				)
			)
		)
		(property "Value" ""
			(at 0 0 0)
			(layer "F.Fab")
			(effects
				(font
					(size 1.27 1.27)
				)
			)
		)
		(duplicate_pad_numbers_are_jumpers no)
		(fp_line
			(start -0.299974 -0.150114)
			(end 0.299974 -0.150114)
			(stroke
				(width 0.1)
				(type default)
			)
			(layer "F.Fab")
		)
		(fp_line
			(start -0.299974 0.150114)
			(end -0.299974 -0.150114)
			(stroke
				(width 0.1)
				(type default)
			)
			(layer "F.Fab")
		)
		(fp_line
			(start 0.299974 -0.150114)
			(end 0.299974 0.150114)
			(stroke
				(width 0.1)
				(type default)
			)
			(layer "F.Fab")
		)
		(fp_line
			(start 0.299974 0.150114)
			(end -0.299974 0.150114)
			(stroke
				(width 0.1)
				(type default)
			)
			(layer "F.Fab")
		)
		(pad "1" smd rect
			(at -0.2667 0)
			(size 0.3048 0.381)
			(layers "F.Cu" "F.Mask" "F.Paste")
			(net "P5E_CPU1_P0_TX_C_DP<14>")
		)
		(pad "2" smd rect
			(at 0.2667 0)
			(size 0.3048 0.381)
			(layers "F.Cu" "F.Mask" "F.Paste")
			(net "P5E_CPU1_P0_TX_DP<14>")
		)
	)
	(footprint ""
		(layer "F.Cu")
		(at 317.709296 -383.88163 -90)
		(property "Reference" "C913"
			(at 0 0 270)
			(layer "F.SilkS")
			(hide yes)
			(effects
				(font
					(size 1.27 1.27)
				)
			)
		)
		(property "Value" ""
			(at 0 0 270)
			(layer "F.Fab")
			(effects
				(font
					(size 1.27 1.27)
				)
			)
		)
		(duplicate_pad_numbers_are_jumpers no)
		(fp_line
			(start -0.299974 0.150114)
			(end -0.299974 -0.150114)
			(stroke
				(width 0.1)
				(type default)
			)
			(layer "F.Fab")
		)
		(fp_line
			(start 0.299974 0.150114)
			(end -0.299974 0.150114)
			(stroke
				(width 0.1)
				(type default)
			)
			(layer "F.Fab")
		)
		(fp_line
			(start -0.299974 -0.150114)
			(end 0.299974 -0.150114)
			(stroke
				(width 0.1)
				(type default)
			)
			(layer "F.Fab")
		)
		(fp_line
			(start 0.299974 -0.150114)
			(end 0.299974 0.150114)
			(stroke
				(width 0.1)
				(type default)
			)
			(layer "F.Fab")
		)
		(pad "1" smd rect
			(at -0.2667 0 270)
			(size 0.3048 0.381)
			(layers "F.Cu" "F.Mask" "F.Paste")
			(net "P5E_CPU0_P0_TX_C_DP<10>")
		)
		(pad "2" smd rect
			(at 0.2667 0 270)
			(size 0.3048 0.381)
			(layers "F.Cu" "F.Mask" "F.Paste")
			(net "P5E_CPU0_P0_TX_DP<10>")
		)
	)
)
